# BASEBOARD_FAB2 (Tioga Pass) — schematic netlist excerpt (pin names and nets, part order shuffled) for the footprints in the layout excerpt that follows; sources: Cadence DE-HDL packaged netlist, KiCad conversion of Wiwynn_Tioga_Pass_MB.brd

R9P9  RES  3.74K 1% CHIP  pkg 0402  page 200 : A = A_P12V_STBY_ADR_TRIGGER ; B = AGND_HSC
R2T36  374R2F-1-GP  1%  pkg SMD-RG  page 93 : \1\ = P3V3 ; \2\ = P0V7_GTL2104_5_VREF
C3L1  SC1U10V2KX-4-GP  10%  pkg SMD-BCG6  page 236 : \1\ = P5V_STBY ; \2\ = GND

(kicad_pcb
	(version 20260206)
	(generator "pcbnew")
	(generator_version "10.0")
	(general
		(thickness 1.6)
		(legacy_teardrops no)
	)
	(paper "A4")
	(title_block
		(title "Wiwynn_Tioga_Pass_MB.brd")
		(comment 1 "Tioga Pass / footprints 2494-2496 of 4770")
	)
	(layers
		(0 "F.Cu" signal "TOP")
		(4 "In1.Cu" signal "L2GND")
		(6 "In2.Cu" signal "L3")
		(8 "In3.Cu" signal "L4GND")
		(10 "In4.Cu" signal "L5")
		(12 "In5.Cu" signal "L6GND")
		(14 "In6.Cu" signal "L7VCC")
		(16 "In7.Cu" signal "L8VCC")
		(18 "In8.Cu" signal "L9GND")
		(20 "In9.Cu" signal "L10")
		(22 "In10.Cu" signal "L11GND")
		(24 "In11.Cu" signal "L12")
		(26 "In12.Cu" signal "L13GND")
		(2 "B.Cu" signal "BOTTOM")
		(9 "F.Adhes" user "F.Adhesive")
		(11 "B.Adhes" user "B.Adhesive")
		(13 "F.Paste" user "Package Geometry/Pastemask Top")
		(15 "B.Paste" user "Package Geometry/Pastemask Bottom")
		(5 "F.SilkS" user "Ref Des/Silkscreen Top")
		(7 "B.SilkS" user "Ref Des/Silkscreen Bottom")
		(1 "F.Mask" user "Board Geometry/Soldermask Top")
		(3 "B.Mask" user "Board Geometry/Soldermask Bottom")
		(17 "Dwgs.User" user "User.Drawings")
		(19 "Cmts.User" user "User.Comments")
		(21 "Eco1.User" user "User.Eco1")
		(23 "Eco2.User" user "User.Eco2")
		(25 "Edge.Cuts" user "Board Geometry/Outline")
		(27 "Margin" user)
		(31 "F.CrtYd" user "Package Geometry/Place Bound Top")
		(29 "B.CrtYd" user "Package Geometry/Place Bound Bottom")
		(35 "F.Fab" user "Ref Des/Assembly Top")
		(33 "B.Fab" user "Ref Des/Assembly Bottom")
	)
	(footprint ""
		(layer "B.Cu")
		(at 373.4308 -44.8818 90)
		(property "Reference" "R2T36"
			(at 0 0 90)
			(layer "B.SilkS")
			(hide yes)
			(effects
				(font
					(size 1.27 1.27)
				)
				(justify mirror)
			)
		)
		(property "Value" "*"
			(at -0.064008 -4.108196 90)
			(unlocked yes)
			(layer "B.Fab")
			(hide yes)
			(effects
				(font
					(size 1.27 1.016)
					(thickness 0.1524)
				)
				(justify mirror)
			)
		)
		(property "Device Type" "374R2F-1-GP_SMD-RG-374R2F-1-GPA"
			(at -0.064008 -5.632196 90)
			(unlocked yes)
			(layer "B.Fab")
			(hide yes)
			(effects
				(font
					(size 1.27 1.016)
					(thickness 0.1524)
				)
				(justify mirror)
			)
		)
		(duplicate_pad_numbers_are_jumpers no)
		(fp_line
			(start 0.508 -0.9398)
			(end 0.508 0.9398)
			(stroke
				(width 0.1524)
				(type default)
			)
			(layer "B.SilkS")
		)
		(fp_line
			(start -0.508 -0.9398)
			(end 0.508 -0.9398)
			(stroke
				(width 0.1524)
				(type default)
			)
			(layer "B.SilkS")
		)
		(fp_rect
			(start 0.508 0.9398)
			(end -0.508 -0.9398)
			(stroke
				(width 0)
				(type default)
			)
			(fill no)
			(layer "B.CrtYd")
		)
		(fp_rect
			(start 0.508 0.9398)
			(end -0.508 -0.9398)
			(stroke
				(width 0)
				(type default)
			)
			(fill no)
			(layer "B.Fab")
		)
		(pad "1" smd custom
			(at 0 -0.4445 270)
			(size 0.1397 0.1397)
			(layers "B.Cu" "B.Mask" "B.Paste")
			(net "P3V3")
			(options
				(clearance outline)
				(anchor circle)
			)
			(primitives
				(gr_poly
					(pts
						(arc
							(start -0.1778 0.2794)
							(mid -0.249642 0.249642)
							(end -0.2794 0.1778)
						)
						(arc
							(start -0.2794 -0.1778)
							(mid -0.249642 -0.249642)
							(end -0.1778 -0.2794)
						)
						(arc
							(start 0.1778 -0.2794)
							(mid 0.249642 -0.249642)
							(end 0.2794 -0.1778)
						)
						(arc
							(start 0.2794 0.1778)
							(mid 0.249642 0.249642)
							(end 0.1778 0.2794)
						)
					)
					(width 0)
					(fill yes)
				)
			)
		)
		(pad "2" smd custom
			(at 0 0.4445 270)
			(size 0.1397 0.1397)
			(layers "B.Cu" "B.Mask" "B.Paste")
			(net "P0V7_GTL2104_5_VREF")
			(options
				(clearance outline)
				(anchor circle)
			)
			(primitives
				(gr_poly
					(pts
						(arc
							(start -0.1778 0.2794)
							(mid -0.249642 0.249642)
							(end -0.2794 0.1778)
						)
						(arc
							(start -0.2794 -0.1778)
							(mid -0.249642 -0.249642)
							(end -0.1778 -0.2794)
						)
						(arc
							(start 0.1778 -0.2794)
							(mid 0.249642 -0.249642)
							(end 0.2794 -0.1778)
						)
						(arc
							(start 0.2794 0.1778)
							(mid 0.249642 0.249642)
							(end 0.1778 0.2794)
						)
					)
					(width 0)
					(fill yes)
				)
			)
		)
	)
	(footprint ""
		(layer "B.Cu")
		(at 372.51894 -153.956766)
		(property "Reference" "C3L1"
			(at 0 0 0)
			(layer "B.SilkS")
			(hide yes)
			(effects
				(font
					(size 1.27 1.27)
				)
				(justify mirror)
			)
		)
		(property "Value" "*"
			(at -1.1811 -2.8194 0)
			(unlocked yes)
			(layer "B.Fab")
			(hide yes)
			(effects
				(font
					(size 1.27 1.016)
					(thickness 0.1524)
				)
				(justify mirror)
			)
		)
		(property "Device Type" "SC1U10V2KX-4-GP_SMD-BCG6-SC1U1A"
			(at -1.1811 -4.3434 0)
			(unlocked yes)
			(layer "B.Fab")
			(hide yes)
			(effects
				(font
					(size 1.27 1.016)
					(thickness 0.1524)
				)
				(justify mirror)
			)
		)
		(duplicate_pad_numbers_are_jumpers no)
		(fp_rect
			(start 0.4318 0.9525)
			(end -0.4318 -0.9525)
			(stroke
				(width 0)
				(type default)
			)
			(fill no)
			(layer "B.CrtYd")
		)
		(fp_rect
			(start 0.4318 0.9525)
			(end -0.4318 -0.9525)
			(stroke
				(width 0)
				(type default)
			)
			(fill no)
			(layer "B.Fab")
		)
		(pad "1" smd custom
			(at 0 -0.4445 180)
			(size 0.1524 0.1524)
			(layers "B.Cu" "B.Mask" "B.Paste")
			(net "P5V_STBY")
			(options
				(clearance outline)
				(anchor circle)
			)
			(primitives
				(gr_poly
					(pts
						(arc
							(start 0.3048 0.2032)
							(mid 0.275042 0.275042)
							(end 0.2032 0.3048)
						)
						(arc
							(start -0.2032 0.3048)
							(mid -0.275042 0.275042)
							(end -0.3048 0.2032)
						)
						(arc
							(start -0.3048 -0.2032)
							(mid -0.275042 -0.275042)
							(end -0.2032 -0.3048)
						)
						(arc
							(start 0.2032 -0.3048)
							(mid 0.275042 -0.275042)
							(end 0.3048 -0.2032)
						)
					)
					(width 0)
					(fill yes)
				)
			)
		)
		(pad "2" smd custom
			(at 0 0.4445 180)
			(size 0.1524 0.1524)
			(layers "B.Cu" "B.Mask" "B.Paste")
			(net "GND")
			(options
				(clearance outline)
				(anchor circle)
			)
			(primitives
				(gr_poly
					(pts
						(arc
							(start 0.3048 0.2032)
							(mid 0.275042 0.275042)
							(end 0.2032 0.3048)
						)
						(arc
							(start -0.2032 0.3048)
							(mid -0.275042 0.275042)
							(end -0.3048 0.2032)
						)
						(arc
							(start -0.3048 -0.2032)
							(mid -0.275042 -0.275042)
							(end -0.2032 -0.3048)
						)
						(arc
							(start 0.2032 -0.3048)
							(mid 0.275042 -0.275042)
							(end 0.3048 -0.2032)
						)
					)
					(width 0)
					(fill yes)
				)
			)
		)
	)
	(footprint ""
		(layer "B.Cu")
		(at 19.431 -83.312 -90)
		(property "Reference" "R9P9"
			(at 0 0 90)
			(layer "B.SilkS")
			(hide yes)
			(effects
				(font
					(size 1.27 1.27)
				)
				(justify mirror)
			)
		)
		(property "Value" ""
			(at 0 0 90)
			(layer "B.Fab")
			(effects
				(font
					(size 1.27 1.27)
				)
				(justify mirror)
			)
		)
		(duplicate_pad_numbers_are_jumpers no)
		(fp_poly
			(pts
				(xy 0.2794 -0.1016) (xy -0.2794 -0.1016) (xy -0.2794 0.9906) (xy 0.2794 0.9906)
			)
			(stroke
				(width 0)
				(type default)
			)
			(fill no)
			(layer "B.CrtYd")
		)
		(fp_line
			(start -0.2794 0.9906)
			(end -0.2794 -0.1016)
			(stroke
				(width 0.1)
				(type default)
			)
			(layer "B.Fab")
		)
		(fp_line
			(start 0.2794 0.9906)
			(end -0.2794 0.9906)
			(stroke
				(width 0.1)
				(type default)
			)
			(layer "B.Fab")
		)
		(fp_line
			(start -0.2794 -0.1016)
			(end 0.2794 -0.1016)
			(stroke
				(width 0.1)
				(type default)
			)
			(layer "B.Fab")
		)
		(fp_line
			(start 0.2794 -0.1016)
			(end 0.2794 0.9906)
			(stroke
				(width 0.1)
				(type default)
			)
			(layer "B.Fab")
		)
		(pad "1" smd rect
			(at 0 0 90)
			(size 0.508 0.508)
			(layers "B.Cu" "B.Mask" "B.Paste")
			(net "A_P12V_STBY_ADR_TRIGGER")
		)
		(pad "2" smd rect
			(at 0 0.889 90)
			(size 0.508 0.508)
			(layers "B.Cu" "B.Mask" "B.Paste")
			(net "AGND_HSC")
		)
		(zone
			(layer "B.Cu")
			(hatch none 0.5)
			(connect_pads
				(clearance 0)
			)
			(min_thickness 0.25)
			(keepout
				(tracks not_allowed)
				(vias allowed)
				(pads allowed)
				(copperpour not_allowed)
				(footprints allowed)
			)
			(placement
				(enabled no)
				(sheetname "")
			)
			(fill
				(thermal_gap 0.5)
				(thermal_bridge_width 0.5)
				(island_removal_mode 0)
			)
			(polygon
				(pts
					(xy 18.796 -83.058) (xy 18.796 -83.566) (xy 19.177 -83.566) (xy 19.177 -83.058)
				)
			)
		)
		(zone
			(layer "B.Cu")
			(hatch none 0.5)
			(connect_pads
				(clearance 0)
			)
			(min_thickness 0.25)
			(keepout
				(tracks allowed)
				(vias not_allowed)
				(pads allowed)
				(copperpour not_allowed)
				(footprints allowed)
			)
			(placement
				(enabled no)
				(sheetname "")
			)
			(fill
				(thermal_gap 0.5)
				(thermal_bridge_width 0.5)
				(island_removal_mode 0)
			)
			(polygon
				(pts
					(xy 19.177 -83.058) (xy 19.177 -83.566) (xy 18.796 -83.566) (xy 18.796 -83.058)
				)
			)
		)
	)
)
